# T6G (Grand Teton) — schematic netlist excerpt (pin names and nets, part order shuffled) for the footprints in the layout excerpt that follows; sources: Cadence DE-HDL packaged netlist, KiCad conversion of 04192023_DAF0TMB3IC0_F0TG_MB_C_brd_V02_OCP.brd

R8008  Q_RES  33 5% CHIP  pkg 0402LF  page 77 : A = SPI_CPU0_D1 ; B = SPI_CPU0_R1_D1
C1543  Q_CAP_DIFFBUS  DIFF BUS_0.22UF 6.3V 20% X6S  pkg C0201  page 67 : \1\ = P5E_CPU1_P3_TX_C_DP<2> ; \2\ = P5E_CPU1_P3_TX_DP<2>
R6300  Q_RES  0 5% CHIP  pkg 0402LF  page 178 : A = USB_HUB2_MRP_CFG_BC_EN ; B = USB_HUB2_TI_OVERCUR3_MRP_CFG_BC_EN

(kicad_pcb
	(version 20260206)
	(generator "pcbnew")
	(generator_version "10.0")
	(general
		(thickness 1.6)
		(legacy_teardrops no)
	)
	(paper "A4")
	(title_block
		(title "04192023_DAF0TMB3IC0_F0TG_MB_C_brd_V02_OCP.brd")
		(comment 1 "Grand Teton / footprints 911-913 of 8354")
	)
	(layers
		(0 "F.Cu" signal "TOP")
		(4 "In1.Cu" signal "GND")
		(6 "In2.Cu" signal "IN1")
		(8 "In3.Cu" signal "GND1")
		(10 "In4.Cu" signal "IN2")
		(12 "In5.Cu" signal "GND2")
		(14 "In6.Cu" signal "IN3")
		(16 "In7.Cu" signal "GND3")
		(18 "In8.Cu" signal "VCC")
		(20 "In9.Cu" signal "VCC1")
		(22 "In10.Cu" signal "GND4")
		(24 "In11.Cu" signal "IN4")
		(26 "In12.Cu" signal "GND5")
		(28 "In13.Cu" signal "IN5")
		(30 "In14.Cu" signal "GND6")
		(32 "In15.Cu" signal "IN6")
		(34 "In16.Cu" signal "GND7")
		(2 "B.Cu" signal "BOTTOM")
		(9 "F.Adhes" user "F.Adhesive")
		(11 "B.Adhes" user "B.Adhesive")
		(13 "F.Paste" user "Package Geometry/Pastemask Top")
		(15 "B.Paste" user "Package Geometry/Pastemask Bottom")
		(5 "F.SilkS" user "Ref Des/Silkscreen Top")
		(7 "B.SilkS" user "Ref Des/Silkscreen Bottom")
		(1 "F.Mask" user "Board Geometry/Soldermask Top")
		(3 "B.Mask" user "Board Geometry/Soldermask Bottom")
		(17 "Dwgs.User" user "User.Drawings")
		(19 "Cmts.User" user "User.Comments")
		(21 "Eco1.User" user "User.Eco1")
		(23 "Eco2.User" user "User.Eco2")
		(25 "Edge.Cuts" user "Board Geometry/Outline")
		(27 "Margin" user)
		(31 "F.CrtYd" user "Package Geometry/Place Bound Top")
		(29 "B.CrtYd" user "Package Geometry/Place Bound Bottom")
		(35 "F.Fab" user "Ref Des/Assembly Top")
		(33 "B.Fab" user "Ref Des/Assembly Bottom")
	)
	(footprint ""
		(layer "F.Cu")
		(at 113.613946 -52.86248 -90)
		(property "Reference" "R6300"
			(at 0 0 270)
			(layer "F.SilkS")
			(hide yes)
			(effects
				(font
					(size 1.27 1.27)
				)
			)
		)
		(property "Value" ""
			(at 0 0 270)
			(layer "F.Fab")
			(effects
				(font
					(size 1.27 1.27)
				)
			)
		)
		(duplicate_pad_numbers_are_jumpers no)
		(fp_line
			(start -0.7874 0.4064)
			(end -0.7874 -0.4064)
			(stroke
				(width 0.1524)
				(type default)
			)
			(layer "F.SilkS")
		)
		(fp_line
			(start 0.7874 0.4064)
			(end -0.7874 0.4064)
			(stroke
				(width 0.1524)
				(type default)
			)
			(layer "F.SilkS")
		)
		(fp_line
			(start -0.7874 -0.4064)
			(end 0.7874 -0.4064)
			(stroke
				(width 0.1524)
				(type default)
			)
			(layer "F.SilkS")
		)
		(fp_line
			(start 0.7874 -0.4064)
			(end 0.7874 0.4064)
			(stroke
				(width 0.1524)
				(type default)
			)
			(layer "F.SilkS")
		)
		(fp_line
			(start -0.67945 0.3048)
			(end -0.67945 -0.305054)
			(stroke
				(width 0.1)
				(type default)
			)
			(layer "F.Fab")
		)
		(fp_line
			(start -0.12065 0.3048)
			(end -0.67945 0.3048)
			(stroke
				(width 0.1)
				(type default)
			)
			(layer "F.Fab")
		)
		(fp_line
			(start 0.120396 0.3048)
			(end 0.120396 0.2794)
			(stroke
				(width 0.1)
				(type default)
			)
			(layer "F.Fab")
		)
		(fp_line
			(start 0.67945 0.3048)
			(end 0.120396 0.3048)
			(stroke
				(width 0.1)
				(type default)
			)
			(layer "F.Fab")
		)
		(fp_line
			(start -0.12065 0.2794)
			(end -0.12065 0.3048)
			(stroke
				(width 0.1)
				(type default)
			)
			(layer "F.Fab")
		)
		(fp_line
			(start 0.120396 0.2794)
			(end -0.12065 0.2794)
			(stroke
				(width 0.1)
				(type default)
			)
			(layer "F.Fab")
		)
		(fp_line
			(start -0.12065 -0.2794)
			(end 0.12065 -0.2794)
			(stroke
				(width 0.1)
				(type default)
			)
			(layer "F.Fab")
		)
		(fp_line
			(start 0.12065 -0.2794)
			(end 0.12065 -0.3048)
			(stroke
				(width 0.1)
				(type default)
			)
			(layer "F.Fab")
		)
		(fp_line
			(start 0.12065 -0.3048)
			(end 0.67945 -0.3048)
			(stroke
				(width 0.1)
				(type default)
			)
			(layer "F.Fab")
		)
		(fp_line
			(start 0.67945 -0.3048)
			(end 0.67945 0.3048)
			(stroke
				(width 0.1)
				(type default)
			)
			(layer "F.Fab")
		)
		(fp_line
			(start -0.67945 -0.305054)
			(end -0.12065 -0.305054)
			(stroke
				(width 0.1)
				(type default)
			)
			(layer "F.Fab")
		)
		(fp_line
			(start -0.12065 -0.305054)
			(end -0.12065 -0.2794)
			(stroke
				(width 0.1)
				(type default)
			)
			(layer "F.Fab")
		)
		(pad "1" smd circle
			(at -0.40005 0 270)
			(size 0 0)
			(layers "F.Cu" "F.Mask" "F.Paste")
			(net "USB_HUB2_MRP_CFG_BC_EN")
		)
		(pad "2" smd circle
			(at 0.40005 0 270)
			(size 0 0)
			(layers "F.Cu" "F.Mask" "F.Paste")
			(net "USB_HUB2_TI_OVERCUR3_MRP_CFG_BC_EN")
		)
	)
	(footprint ""
		(layer "F.Cu")
		(at 261.62 -141.986 -90)
		(property "Reference" "R8008"
			(at 0 0 270)
			(layer "F.SilkS")
			(hide yes)
			(effects
				(font
					(size 1.27 1.27)
				)
			)
		)
		(property "Value" ""
			(at 0 0 270)
			(layer "F.Fab")
			(effects
				(font
					(size 1.27 1.27)
				)
			)
		)
		(duplicate_pad_numbers_are_jumpers no)
		(fp_line
			(start -0.7874 0.4064)
			(end -0.7874 -0.4064)
			(stroke
				(width 0.1524)
				(type default)
			)
			(layer "F.SilkS")
		)
		(fp_line
			(start 0.7874 0.4064)
			(end -0.7874 0.4064)
			(stroke
				(width 0.1524)
				(type default)
			)
			(layer "F.SilkS")
		)
		(fp_line
			(start -0.7874 -0.4064)
			(end 0.7874 -0.4064)
			(stroke
				(width 0.1524)
				(type default)
			)
			(layer "F.SilkS")
		)
		(fp_line
			(start 0.7874 -0.4064)
			(end 0.7874 0.4064)
			(stroke
				(width 0.1524)
				(type default)
			)
			(layer "F.SilkS")
		)
		(fp_line
			(start -0.67945 0.3048)
			(end -0.67945 -0.305054)
			(stroke
				(width 0.1)
				(type default)
			)
			(layer "F.Fab")
		)
		(fp_line
			(start -0.12065 0.3048)
			(end -0.67945 0.3048)
			(stroke
				(width 0.1)
				(type default)
			)
			(layer "F.Fab")
		)
		(fp_line
			(start 0.120396 0.3048)
			(end 0.120396 0.2794)
			(stroke
				(width 0.1)
				(type default)
			)
			(layer "F.Fab")
		)
		(fp_line
			(start 0.67945 0.3048)
			(end 0.120396 0.3048)
			(stroke
				(width 0.1)
				(type default)
			)
			(layer "F.Fab")
		)
		(fp_line
			(start -0.12065 0.2794)
			(end -0.12065 0.3048)
			(stroke
				(width 0.1)
				(type default)
			)
			(layer "F.Fab")
		)
		(fp_line
			(start 0.120396 0.2794)
			(end -0.12065 0.2794)
			(stroke
				(width 0.1)
				(type default)
			)
			(layer "F.Fab")
		)
		(fp_line
			(start -0.12065 -0.2794)
			(end 0.12065 -0.2794)
			(stroke
				(width 0.1)
				(type default)
			)
			(layer "F.Fab")
		)
		(fp_line
			(start 0.12065 -0.2794)
			(end 0.12065 -0.3048)
			(stroke
				(width 0.1)
				(type default)
			)
			(layer "F.Fab")
		)
		(fp_line
			(start 0.12065 -0.3048)
			(end 0.67945 -0.3048)
			(stroke
				(width 0.1)
				(type default)
			)
			(layer "F.Fab")
		)
		(fp_line
			(start 0.67945 -0.3048)
			(end 0.67945 0.3048)
			(stroke
				(width 0.1)
				(type default)
			)
			(layer "F.Fab")
		)
		(fp_line
			(start -0.67945 -0.305054)
			(end -0.12065 -0.305054)
			(stroke
				(width 0.1)
				(type default)
			)
			(layer "F.Fab")
		)
		(fp_line
			(start -0.12065 -0.305054)
			(end -0.12065 -0.2794)
			(stroke
				(width 0.1)
				(type default)
			)
			(layer "F.Fab")
		)
		(pad "1" smd circle
			(at -0.40005 0 270)
			(size 0 0)
			(layers "F.Cu" "F.Mask" "F.Paste")
			(net "SPI_CPU0_D1")
		)
		(pad "2" smd circle
			(at 0.40005 0 270)
			(size 0 0)
			(layers "F.Cu" "F.Mask" "F.Paste")
			(net "SPI_CPU0_R1_D1")
		)
	)
	(footprint ""
		(layer "F.Cu")
		(at 110.089696 -373.03583 -90)
		(property "Reference" "C1543"
			(at 0 0 270)
			(layer "F.SilkS")
			(hide yes)
			(effects
				(font
					(size 1.27 1.27)
				)
			)
		)
		(property "Value" ""
			(at 0 0 270)
			(layer "F.Fab")
			(effects
				(font
					(size 1.27 1.27)
				)
			)
		)
		(duplicate_pad_numbers_are_jumpers no)
		(fp_line
			(start -0.299974 0.150114)
			(end -0.299974 -0.150114)
			(stroke
				(width 0.1)
				(type default)
			)
			(layer "F.Fab")
		)
		(fp_line
			(start 0.299974 0.150114)
			(end -0.299974 0.150114)
			(stroke
				(width 0.1)
				(type default)
			)
			(layer "F.Fab")
		)
		(fp_line
			(start -0.299974 -0.150114)
			(end 0.299974 -0.150114)
			(stroke
				(width 0.1)
				(type default)
			)
			(layer "F.Fab")
		)
		(fp_line
			(start 0.299974 -0.150114)
			(end 0.299974 0.150114)
			(stroke
				(width 0.1)
				(type default)
			)
			(layer "F.Fab")
		)
		(pad "1" smd rect
			(at -0.2667 0 270)
			(size 0.3048 0.381)
			(layers "F.Cu" "F.Mask" "F.Paste")
			(net "P5E_CPU1_P3_TX_C_DP<2>")
		)
		(pad "2" smd rect
			(at 0.2667 0 270)
			(size 0.3048 0.381)
			(layers "F.Cu" "F.Mask" "F.Paste")
			(net "P5E_CPU1_P3_TX_DP<2>")
		)
	)
)
